(kicad_pcb
	(version 20260206)
	(generator "pcbnew")
	(generator_version "10.0")
	(general
		(thickness 1.6)
		(legacy_teardrops no)
	)
	(paper "A4")
	(title_block
		(title "peb — Lightning_PEB_BRD.brd")
		(comment 1 "Lightning (Wiwynn / Facebook NVMe JBOF) / footprints 1211-1215 of 2563")
	)
	(layers
		(0 "F.Cu" signal "TOP")
		(4 "In1.Cu" signal "L2GND")
		(6 "In2.Cu" signal "L3")
		(8 "In3.Cu" signal "L4VCC")
		(10 "In4.Cu" signal "L5VCC")
		(12 "In5.Cu" signal "L6")
		(14 "In6.Cu" signal "L7GND")
		(2 "B.Cu" signal "BOTTOM")
		(9 "F.Adhes" user "F.Adhesive")
		(11 "B.Adhes" user "B.Adhesive")
		(13 "F.Paste" user "Package Geometry/Pastemask Top")
		(15 "B.Paste" user "Package Geometry/Pastemask Bottom")
		(5 "F.SilkS" user "Ref Des/Silkscreen Top")
		(7 "B.SilkS" user "Ref Des/Silkscreen Bottom")
		(1 "F.Mask" user "Board Geometry/Soldermask Top")
		(3 "B.Mask" user "Board Geometry/Soldermask Bottom")
		(17 "Dwgs.User" user "User.Drawings")
		(19 "Cmts.User" user "User.Comments")
		(21 "Eco1.User" user "User.Eco1")
		(23 "Eco2.User" user "User.Eco2")
		(25 "Edge.Cuts" user "Board Geometry/Outline")
		(27 "Margin" user)
		(31 "F.CrtYd" user "Package Geometry/Place Bound Top")
		(29 "B.CrtYd" user "Package Geometry/Place Bound Bottom")
		(35 "F.Fab" user "Ref Des/Assembly Top")
		(33 "B.Fab" user "Ref Des/Assembly Bottom")
	)
	(footprint ""
		(layer "F.Cu")
		(at 72.1868 -120.0912 180)
		(property "Reference" "R567"
			(at 0 0 180)
			(layer "F.SilkS")
			(hide yes)
			(effects
				(font
					(size 1.27 1.27)
				)
			)
		)
		(property "Value" "4K7R2F-GP"
			(at 0.064008 -3.993896 180)
			(unlocked yes)
			(layer "F.Fab")
			(hide yes)
			(effects
				(font
					(size 1.016 1.016)
					(thickness 0.1524)
				)
			)
		)
		(property "Device Type" "R402H16"
			(at 0.064008 -5.517896 180)
			(unlocked yes)
			(layer "F.Fab")
			(hide yes)
			(effects
				(font
					(size 1.016 1.016)
					(thickness 0.1524)
				)
			)
		)
		(duplicate_pad_numbers_are_jumpers no)
		(fp_line
			(start 0.508 -0.9398)
			(end -0.508 -0.9398)
			(stroke
				(width 0.1524)
				(type default)
			)
			(layer "F.SilkS")
		)
		(fp_line
			(start -0.508 -0.9398)
			(end -0.508 0.9398)
			(stroke
				(width 0.1524)
				(type default)
			)
			(layer "F.SilkS")
		)
		(fp_rect
			(start -0.508 0.9398)
			(end 0.508 -0.9398)
			(stroke
				(width 0)
				(type default)
			)
			(fill no)
			(layer "F.CrtYd")
		)
		(fp_rect
			(start -0.508 0.9398)
			(end 0.508 -0.9398)
			(stroke
				(width 0)
				(type default)
			)
			(fill no)
			(layer "F.Fab")
		)
		(pad "1" smd custom
			(at 0 -0.4445 180)
			(size 0.1397 0.1397)
			(layers "F.Cu" "F.Mask" "F.Paste")
			(net "P3V3_STBY")
			(options
				(clearance outline)
				(anchor circle)
			)
			(primitives
				(gr_poly
					(pts
						(arc
							(start -0.1778 -0.2794)
							(mid -0.249642 -0.249642)
							(end -0.2794 -0.1778)
						)
						(arc
							(start -0.2794 0.1778)
							(mid -0.249642 0.249642)
							(end -0.1778 0.2794)
						)
						(arc
							(start 0.1778 0.2794)
							(mid 0.249642 0.249642)
							(end 0.2794 0.1778)
						)
						(arc
							(start 0.2794 -0.1778)
							(mid 0.249642 -0.249642)
							(end 0.1778 -0.2794)
						)
					)
					(width 0)
					(fill yes)
				)
			)
		)
		(pad "2" smd custom
			(at 0 0.4445 180)
			(size 0.1397 0.1397)
			(layers "F.Cu" "F.Mask" "F.Paste")
			(net "BMC_RXD5_R")
			(options
				(clearance outline)
				(anchor circle)
			)
			(primitives
				(gr_poly
					(pts
						(arc
							(start -0.1778 -0.2794)
							(mid -0.249642 -0.249642)
							(end -0.2794 -0.1778)
						)
						(arc
							(start -0.2794 0.1778)
							(mid -0.249642 0.249642)
							(end -0.1778 0.2794)
						)
						(arc
							(start 0.1778 0.2794)
							(mid 0.249642 0.249642)
							(end 0.2794 0.1778)
						)
						(arc
							(start 0.2794 -0.1778)
							(mid 0.249642 -0.249642)
							(end 0.1778 -0.2794)
						)
					)
					(width 0)
					(fill yes)
				)
			)
		)
	)
	(footprint ""
		(layer "F.Cu")
		(at 14.605 -127.508 -90)
		(property "Reference" "R296"
			(at 0 0 270)
			(layer "F.SilkS")
			(hide yes)
			(effects
				(font
					(size 1.27 1.27)
				)
			)
		)
		(property "Value" "4K7R2F-GP"
			(at 0.064008 -3.993896 270)
			(unlocked yes)
			(layer "F.Fab")
			(hide yes)
			(effects
				(font
					(size 1.016 1.016)
					(thickness 0.1524)
				)
			)
		)
		(property "Device Type" "R402H16"
			(at 0.064008 -5.517896 270)
			(unlocked yes)
			(layer "F.Fab")
			(hide yes)
			(effects
				(font
					(size 1.016 1.016)
					(thickness 0.1524)
				)
			)
		)
		(duplicate_pad_numbers_are_jumpers no)
		(fp_line
			(start -0.508 -0.9398)
			(end -0.508 0.9398)
			(stroke
				(width 0.1524)
				(type default)
			)
			(layer "F.SilkS")
		)
		(fp_line
			(start 0.508 -0.9398)
			(end -0.508 -0.9398)
			(stroke
				(width 0.1524)
				(type default)
			)
			(layer "F.SilkS")
		)
		(fp_rect
			(start -0.508 0.9398)
			(end 0.508 -0.9398)
			(stroke
				(width 0)
				(type default)
			)
			(fill no)
			(layer "F.CrtYd")
		)
		(fp_rect
			(start -0.508 0.9398)
			(end 0.508 -0.9398)
			(stroke
				(width 0)
				(type default)
			)
			(fill no)
			(layer "F.Fab")
		)
		(pad "1" smd custom
			(at 0 -0.4445 270)
			(size 0.1397 0.1397)
			(layers "F.Cu" "F.Mask" "F.Paste")
			(net "P3V3_STBY")
			(options
				(clearance outline)
				(anchor circle)
			)
			(primitives
				(gr_poly
					(pts
						(arc
							(start -0.1778 -0.2794)
							(mid -0.249642 -0.249642)
							(end -0.2794 -0.1778)
						)
						(arc
							(start -0.2794 0.1778)
							(mid -0.249642 0.249642)
							(end -0.1778 0.2794)
						)
						(arc
							(start 0.1778 0.2794)
							(mid 0.249642 0.249642)
							(end 0.2794 0.1778)
						)
						(arc
							(start 0.2794 -0.1778)
							(mid 0.249642 -0.249642)
							(end 0.1778 -0.2794)
						)
					)
					(width 0)
					(fill yes)
				)
			)
		)
		(pad "2" smd custom
			(at 0 0.4445 270)
			(size 0.1397 0.1397)
			(layers "F.Cu" "F.Mask" "F.Paste")
			(net "I2C2_LS_G1")
			(options
				(clearance outline)
				(anchor circle)
			)
			(primitives
				(gr_poly
					(pts
						(arc
							(start -0.1778 -0.2794)
							(mid -0.249642 -0.249642)
							(end -0.2794 -0.1778)
						)
						(arc
							(start -0.2794 0.1778)
							(mid -0.249642 0.249642)
							(end -0.1778 0.2794)
						)
						(arc
							(start 0.1778 0.2794)
							(mid 0.249642 0.249642)
							(end 0.2794 0.1778)
						)
						(arc
							(start 0.2794 -0.1778)
							(mid 0.249642 -0.249642)
							(end 0.1778 -0.2794)
						)
					)
					(width 0)
					(fill yes)
				)
			)
		)
	)
	(footprint ""
		(layer "F.Cu")
		(at 5.5626 -49.3014 180)
		(property "Reference" "C329"
			(at 0 0 180)
			(layer "F.SilkS")
			(hide yes)
			(effects
				(font
					(size 1.27 1.27)
				)
			)
		)
		(property "Value" "SCD1U16V2KX-3GP"
			(at 1.1811 -2.7051 180)
			(unlocked yes)
			(layer "F.Fab")
			(hide yes)
			(effects
				(font
					(size 1.016 1.016)
					(thickness 0.1524)
				)
			)
		)
		(property "Device Type" "C402H22"
			(at 1.1811 -4.2291 180)
			(unlocked yes)
			(layer "F.Fab")
			(hide yes)
			(effects
				(font
					(size 1.016 1.016)
					(thickness 0.1524)
				)
			)
		)
		(duplicate_pad_numbers_are_jumpers no)
		(fp_rect
			(start -0.4318 0.9525)
			(end 0.4318 -0.9525)
			(stroke
				(width 0)
				(type default)
			)
			(fill no)
			(layer "F.CrtYd")
		)
		(fp_rect
			(start -0.4318 0.9525)
			(end 0.4318 -0.9525)
			(stroke
				(width 0)
				(type default)
			)
			(fill no)
			(layer "F.Fab")
		)
		(pad "1" smd custom
			(at 0 -0.4445 180)
			(size 0.1524 0.1524)
			(layers "F.Cu" "F.Mask" "F.Paste")
			(net "NIC0_CT_POWER")
			(options
				(clearance outline)
				(anchor circle)
			)
			(primitives
				(gr_poly
					(pts
						(arc
							(start 0.3048 -0.2032)
							(mid 0.275042 -0.275042)
							(end 0.2032 -0.3048)
						)
						(arc
							(start -0.2032 -0.3048)
							(mid -0.275042 -0.275042)
							(end -0.3048 -0.2032)
						)
						(arc
							(start -0.3048 0.2032)
							(mid -0.275042 0.275042)
							(end -0.2032 0.3048)
						)
						(arc
							(start 0.2032 0.3048)
							(mid 0.275042 0.275042)
							(end 0.3048 0.2032)
						)
					)
					(width 0)
					(fill yes)
				)
			)
		)
		(pad "2" smd custom
			(at 0 0.4445 180)
			(size 0.1524 0.1524)
			(layers "F.Cu" "F.Mask" "F.Paste")
			(net "GND")
			(options
				(clearance outline)
				(anchor circle)
			)
			(primitives
				(gr_poly
					(pts
						(arc
							(start 0.3048 -0.2032)
							(mid 0.275042 -0.275042)
							(end 0.2032 -0.3048)
						)
						(arc
							(start -0.2032 -0.3048)
							(mid -0.275042 -0.275042)
							(end -0.3048 -0.2032)
						)
						(arc
							(start -0.3048 0.2032)
							(mid -0.275042 0.275042)
							(end -0.2032 0.3048)
						)
						(arc
							(start 0.2032 0.3048)
							(mid 0.275042 0.275042)
							(end 0.3048 0.2032)
						)
					)
					(width 0)
					(fill yes)
				)
			)
		)
	)
	(footprint ""
		(layer "F.Cu")
		(at 138.6586 -46.736)
		(property "Reference" "CN5"
			(at 0 0 0)
			(layer "F.SilkS")
			(hide yes)
			(effects
				(font
					(size 1.27 1.27)
				)
			)
		)
		(property "Value" "MLX-CONN14A-16-GP"
			(at -6.941312 -6.705854 0)
			(unlocked yes)
			(layer "F.Fab")
			(hide yes)
			(effects
				(font
					(size 1.016 1.016)
					(thickness 0.1524)
				)
			)
		)
		(property "Device Type" "87332-1420-1"
			(at -6.941312 -8.229854 0)
			(unlocked yes)
			(layer "F.Fab")
			(hide yes)
			(effects
				(font
					(size 1.016 1.016)
					(thickness 0.1524)
				)
			)
		)
		(duplicate_pad_numbers_are_jumpers no)
		(fp_line
			(start -8.5852 -3.7465)
			(end -8.5852 3.7465)
			(stroke
				(width 0.1524)
				(type default)
			)
			(layer "F.SilkS")
		)
		(fp_line
			(start -8.5852 3.7465)
			(end 8.5852 3.7465)
			(stroke
				(width 0.1524)
				(type default)
			)
			(layer "F.SilkS")
		)
		(fp_line
			(start -6.5024 3.8608)
			(end -5.4356 3.8608)
			(stroke
				(width 0.3302)
				(type default)
			)
			(layer "F.SilkS")
		)
		(fp_line
			(start 8.5852 -3.7465)
			(end -8.5852 -3.7465)
			(stroke
				(width 0.1524)
				(type default)
			)
			(layer "F.SilkS")
		)
		(fp_line
			(start 8.5852 3.7465)
			(end 8.5852 -3.7465)
			(stroke
				(width 0.1524)
				(type default)
			)
			(layer "F.SilkS")
		)
		(fp_poly
			(pts
				(xy -5.969 3.8227) (xy -6.477 4.3307) (xy -5.461 4.3307)
			)
			(stroke
				(width 0)
				(type default)
			)
			(fill yes)
			(layer "F.SilkS")
		)
		(fp_poly
			(pts
				(xy -4.18719 -0.550164) (xy -4.18719 0.550164) (xy 4.18719 0.550164) (xy 4.18719 -0.550164)
			)
			(stroke
				(width 0)
				(type default)
			)
			(fill yes)
			(layer "F.SilkS")
		)
		(fp_rect
			(start -8.3312 3.1496)
			(end 8.3312 -3.1496)
			(stroke
				(width 0)
				(type default)
			)
			(fill no)
			(layer "F.CrtYd")
		)
		(fp_poly
			(pts
				(xy -8.8392 4.0005) (xy -8.8392 -4.0005) (xy 8.8392 -4.0005) (xy 8.8392 4.0005) (xy 0.00254 4.0005)
				(xy 0.00254 3.1496) (xy 8.3312 3.1496) (xy 8.3312 -3.1496) (xy -8.3312 -3.1496) (xy -8.3312 3.1496)
				(xy -0.00254 3.1496) (xy -0.00254 4.0005)
			)
			(stroke
				(width 0)
				(type default)
			)
			(fill no)
			(layer "F.CrtYd")
		)
		(fp_rect
			(start -8.8392 4.0005)
			(end 8.8392 -4.0005)
			(stroke
				(width 0)
				(type default)
			)
			(fill no)
			(layer "F.Fab")
		)
		(pad "" np_thru_hole circle
			(at -4.99999 0)
			(size 0.254 0.254)
			(drill 1.016)
			(layers "*.Cu" "*.Mask")
			(clearance 0.7366)
			(thermal_gap 0.7366)
		)
		(pad "" np_thru_hole circle
			(at 4.99999 0)
			(size 0.254 0.254)
			(drill 1.016)
			(layers "*.Cu" "*.Mask")
			(clearance 0.7366)
			(thermal_gap 0.7366)
		)
		(pad "1" smd rect
			(at -5.999988 2.124964)
			(size 0.9906 2.7432)
			(layers "F.Cu" "F.Mask" "F.Paste")
			(net "EJTAG_TRSTB")
		)
		(pad "2" smd rect
			(at -5.999988 -2.124964)
			(size 0.9906 2.7432)
			(layers "F.Cu" "F.Mask" "F.Paste")
			(net "GND")
		)
		(pad "3" smd rect
			(at -3.999992 2.124964)
			(size 0.9906 2.7432)
			(layers "F.Cu" "F.Mask" "F.Paste")
			(net "EJTAG_TDI")
		)
		(pad "4" smd rect
			(at -3.999992 -2.124964)
			(size 0.9906 2.7432)
			(layers "F.Cu" "F.Mask" "F.Paste")
			(net "GND")
		)
		(pad "5" smd rect
			(at -1.999996 2.124964)
			(size 0.9906 2.7432)
			(layers "F.Cu" "F.Mask" "F.Paste")
			(net "EJTAG_TDO")
		)
		(pad "6" smd rect
			(at -1.999996 -2.124964)
			(size 0.9906 2.7432)
			(layers "F.Cu" "F.Mask" "F.Paste")
			(net "GND")
		)
		(pad "7" smd rect
			(at 0 2.124964)
			(size 0.9906 2.7432)
			(layers "F.Cu" "F.Mask" "F.Paste")
			(net "EJTAG_TMS")
		)
		(pad "8" smd rect
			(at 0 -2.124964)
			(size 0.9906 2.7432)
			(layers "F.Cu" "F.Mask" "F.Paste")
			(net "GND")
		)
		(pad "9" smd rect
			(at 1.999996 2.124964)
			(size 0.9906 2.7432)
			(layers "F.Cu" "F.Mask" "F.Paste")
			(net "EJTAG_TCK")
		)
		(pad "10" smd rect
			(at 1.999996 -2.124964)
			(size 0.9906 2.7432)
			(layers "F.Cu" "F.Mask" "F.Paste")
			(net "GND")
		)
		(pad "11" smd rect
			(at 3.999992 2.124964)
			(size 0.9906 2.7432)
			(layers "F.Cu" "F.Mask" "F.Paste")
			(net "EJTAG_RSTB")
		)
		(pad "12" smd rect
			(at 3.999992 -2.124964)
			(size 0.9906 2.7432)
			(layers "F.Cu" "F.Mask" "F.Paste")
			(net "Net_4")
		)
		(pad "13" smd rect
			(at 5.999988 2.124964)
			(size 0.9906 2.7432)
			(layers "F.Cu" "F.Mask" "F.Paste")
			(net "EJTAG_DINT")
		)
		(pad "14" smd rect
			(at 5.999988 -2.124964)
			(size 0.9906 2.7432)
			(layers "F.Cu" "F.Mask" "F.Paste")
			(net "EJTAG_PWR")
		)
		(zone
			(layer "F.Cu")
			(hatch none 0.5)
			(connect_pads
				(clearance 0)
			)
			(min_thickness 0.25)
			(keepout
				(tracks allowed)
				(vias not_allowed)
				(pads allowed)
				(copperpour not_allowed)
				(footprints allowed)
			)
			(placement
				(enabled no)
				(sheetname "")
			)
			(fill
				(thermal_gap 0.5)
				(thermal_bridge_width 0.5)
				(island_removal_mode 0)
			)
			(polygon
				(pts
					(xy 132.163312 -47.489364) (xy 132.163312 -46.981364) (xy 145.153888 -46.981364) (xy 145.153888 -47.489364)
				)
			)
		)
		(zone
			(layer "F.Cu")
			(hatch none 0.5)
			(connect_pads
				(clearance 0)
			)
			(min_thickness 0.25)
			(keepout
				(tracks allowed)
				(vias not_allowed)
				(pads allowed)
				(copperpour not_allowed)
				(footprints allowed)
			)
			(placement
				(enabled no)
				(sheetname "")
			)
			(fill
				(thermal_gap 0.5)
				(thermal_bridge_width 0.5)
				(island_removal_mode 0)
			)
			(polygon
				(pts
					(xy 132.163312 -47.489364) (xy 132.163312 -45.982636) (xy 145.153888 -45.982636) (xy 145.153888 -47.489364)
				)
			)
		)
		(zone
			(layer "F.Cu")
			(hatch none 0.5)
			(connect_pads
				(clearance 0)
			)
			(min_thickness 0.25)
			(keepout
				(tracks not_allowed)
				(vias allowed)
				(pads allowed)
				(copperpour not_allowed)
				(footprints allowed)
			)
			(placement
				(enabled no)
				(sheetname "")
			)
			(fill
				(thermal_gap 0.5)
				(thermal_bridge_width 0.5)
				(island_removal_mode 0)
			)
			(polygon
				(pts
					(xy 132.163312 -47.489364) (xy 132.163312 -45.982636) (xy 145.153888 -45.982636) (xy 145.153888 -47.489364)
				)
			)
		)
		(zone
			(layer "F.Cu")
			(hatch none 0.5)
			(connect_pads
				(clearance 0)
			)
			(min_thickness 0.25)
			(keepout
				(tracks allowed)
				(vias not_allowed)
				(pads allowed)
				(copperpour not_allowed)
				(footprints allowed)
			)
			(placement
				(enabled no)
				(sheetname "")
			)
			(fill
				(thermal_gap 0.5)
				(thermal_bridge_width 0.5)
				(island_removal_mode 0)
			)
			(polygon
				(pts
					(xy 132.163312 -46.490636) (xy 132.163312 -45.982636) (xy 145.153888 -45.982636) (xy 145.153888 -46.490636)
				)
			)
		)
		(zone
			(layers "F.Cu" "B.Cu" "In1.Cu" "In2.Cu" "In3.Cu" "In4.Cu" "In5.Cu" "In6.Cu")
			(hatch none 0.5)
			(connect_pads
				(clearance 0)
			)
			(min_thickness 0.25)
			(keepout
				(tracks not_allowed)
				(vias allowed)
				(pads allowed)
				(copperpour not_allowed)
				(footprints allowed)
			)
			(placement
				(enabled no)
				(sheetname "")
			)
			(fill
				(thermal_gap 0.5)
				(thermal_bridge_width 0.5)
				(island_removal_mode 0)
			)
			(polygon
				(pts
					(arc
						(start 134.47141 -46.736)
						(mid 132.84581 -46.736)
						(end 134.47141 -46.736)
					)
				)
			)
		)
		(zone
			(layers "F.Cu" "B.Cu" "In1.Cu" "In2.Cu" "In3.Cu" "In4.Cu" "In5.Cu" "In6.Cu")
			(hatch none 0.5)
			(connect_pads
				(clearance 0)
			)
			(min_thickness 0.25)
			(keepout
				(tracks not_allowed)
				(vias allowed)
				(pads allowed)
				(copperpour not_allowed)
				(footprints allowed)
			)
			(placement
				(enabled no)
				(sheetname "")
			)
			(fill
				(thermal_gap 0.5)
				(thermal_bridge_width 0.5)
				(island_removal_mode 0)
			)
			(polygon
				(pts
					(arc
						(start 144.47139 -46.736)
						(mid 142.84579 -46.736)
						(end 144.47139 -46.736)
					)
				)
			)
		)
	)
	(footprint ""
		(layer "F.Cu")
		(at 189.611 -7.9248 -90)
		(property "Reference" "U38"
			(at 0 0 270)
			(layer "F.SilkS")
			(hide yes)
			(effects
				(font
					(size 1.27 1.27)
				)
			)
		)
		(property "Value" "SN74LVC1G08DCKR-GP"
			(at -2.3368 -8.6868 270)
			(unlocked yes)
			(layer "F.Fab")
			(hide yes)
			(effects
				(font
					(size 1.016 1.016)
					(thickness 0.1524)
				)
			)
		)
		(property "Device Type" "SC70-5H44"
			(at -2.3114 -10.414 270)
			(unlocked yes)
			(layer "F.Fab")
			(hide yes)
			(effects
				(font
					(size 1.016 1.016)
					(thickness 0.1524)
				)
			)
		)
		(duplicate_pad_numbers_are_jumpers no)
		(fp_line
			(start -1.27 1.7018)
			(end -1.27 -1.7018)
			(stroke
				(width 0.1524)
				(type default)
			)
			(layer "F.SilkS")
		)
		(fp_line
			(start 1.27 1.7018)
			(end -1.27 1.7018)
			(stroke
				(width 0.1524)
				(type default)
			)
			(layer "F.SilkS")
		)
		(fp_line
			(start -1.27 -1.7018)
			(end 1.27 -1.7018)
			(stroke
				(width 0.1524)
				(type default)
			)
			(layer "F.SilkS")
		)
		(fp_line
			(start 1.27 -1.7018)
			(end 1.27 1.7018)
			(stroke
				(width 0.1524)
				(type default)
			)
			(layer "F.SilkS")
		)
		(fp_line
			(start 0.6604 -1.8034)
			(end 1.3843 -1.8034)
			(stroke
				(width 0.3302)
				(type default)
			)
			(layer "F.SilkS")
		)
		(fp_line
			(start 1.3843 -1.8034)
			(end 1.3843 -1.1176)
			(stroke
				(width 0.3302)
				(type default)
			)
			(layer "F.SilkS")
		)
		(fp_rect
			(start -1.524 1.9558)
			(end 1.524 -1.9558)
			(stroke
				(width 0)
				(type default)
			)
			(fill no)
			(layer "F.CrtYd")
		)
		(fp_poly
			(pts
				(xy -1.524 -1.9558) (xy 1.524 -1.9558) (xy 1.524 1.9558) (xy -1.524 1.9558)
			)
			(stroke
				(width 0)
				(type default)
			)
			(fill no)
			(layer "F.Fab")
		)
		(pad "1" smd rect
			(at 0.65024 -0.8255 270)
			(size 0.4064 1.2192)
			(layers "F.Cu" "F.Mask" "F.Paste")
			(net "HB_OUT_R")
		)
		(pad "2" smd rect
			(at 0 -0.8255 270)
			(size 0.4064 1.2192)
			(layers "F.Cu" "F.Mask" "F.Paste")
			(net "BMC_ENCLOSURE_LED_R")
		)
		(pad "3" smd rect
			(at -0.65024 -0.8255 270)
			(size 0.4064 1.2192)
			(layers "F.Cu" "F.Mask" "F.Paste")
			(net "GND")
		)
		(pad "4" smd rect
			(at -0.65024 0.8255 270)
			(size 0.4064 1.2192)
			(layers "F.Cu" "F.Mask" "F.Paste")
			(net "ENCLO_LED_BLUE_OUT")
		)
		(pad "5" smd rect
			(at 0.65024 0.8255 270)
			(size 0.4064 1.2192)
			(layers "F.Cu" "F.Mask" "F.Paste")
			(net "P3V3_STBY")
		)
	)
)
